(kicad_pcb
	(version 20260206)
	(generator "pcbnew")
	(generator_version "10.0")
	(general
		(thickness 1.6)
		(legacy_teardrops no)
	)
	(paper "A4")
	(title_block
		(title "Bryce Canyon_R.DPB_16317-1_OCP.brd")
		(comment 1 "Bryce Canyon / footprint 1685 of 2099 (BUS1), pads 1-60 of 60")
	)
	(layers
		(0 "F.Cu" signal "TOP")
		(4 "In1.Cu" signal "L2GND")
		(6 "In2.Cu" signal "L3")
		(8 "In3.Cu" signal "L4VCC")
		(10 "In4.Cu" signal "L5VCC")
		(12 "In5.Cu" signal "L6")
		(14 "In6.Cu" signal "L7GND")
		(2 "B.Cu" signal "BOTTOM")
		(9 "F.Adhes" user "F.Adhesive")
		(11 "B.Adhes" user "B.Adhesive")
		(13 "F.Paste" user "Package Geometry/Pastemask Top")
		(15 "B.Paste" user "Package Geometry/Pastemask Bottom")
		(5 "F.SilkS" user "Ref Des/Silkscreen Top")
		(7 "B.SilkS" user "Ref Des/Silkscreen Bottom")
		(1 "F.Mask" user "Board Geometry/Soldermask Top")
		(3 "B.Mask" user "Board Geometry/Soldermask Bottom")
		(17 "Dwgs.User" user "User.Drawings")
		(19 "Cmts.User" user "User.Comments")
		(21 "Eco1.User" user "User.Eco1")
		(23 "Eco2.User" user "User.Eco2")
		(25 "Edge.Cuts" user "Board Geometry/Outline")
		(27 "Margin" user)
		(31 "F.CrtYd" user "Package Geometry/Place Bound Top")
		(29 "B.CrtYd" user "Package Geometry/Place Bound Bottom")
		(35 "F.Fab" user "Ref Des/Assembly Top")
		(33 "B.Fab" user "Ref Des/Assembly Bottom")
	)
	(footprint ""
		(layer "F.Cu")
		(at 67.69989 -335.399888)
		(property "Reference" "BUS1"
			(at 0 0 0)
			(layer "F.SilkS")
			(hide yes)
			(effects
				(font
					(size 1.27 1.27)
				)
			)
		)
		(property "Value" "FCI-CONN56-4R-GP"
			(at -15.9385 -18.8976 0)
			(unlocked yes)
			(layer "F.Fab")
			(hide yes)
			(effects
				(font
					(size 1.016 1.016)
					(thickness 0.1524)
				)
			)
		)
		(property "Device Type" "PREFIT-56P-775146-1H510"
			(at -15.9385 -20.4216 0)
			(unlocked yes)
			(layer "F.Fab")
			(hide yes)
			(effects
				(font
					(size 1.016 1.016)
					(thickness 0.1524)
				)
			)
		)
		(duplicate_pad_numbers_are_jumpers no)
		(pad "" np_thru_hole circle
			(at -5.08 0)
			(size 0.254 0.254)
			(drill 3.2004)
			(layers "*.Cu" "*.Mask")
			(clearance 1.8288)
			(thermal_gap 1.8288)
		)
		(pad "" np_thru_hole circle
			(at 0 0)
			(size 0.254 0.254)
			(drill 2.5146)
			(layers "*.Cu" "*.Mask")
			(clearance 1.4859)
			(thermal_gap 1.4859)
		)
		(pad "" np_thru_hole circle
			(at 62.23 0)
			(size 0.254 0.254)
			(drill 2.5146)
			(layers "*.Cu" "*.Mask")
			(clearance 1.4859)
			(thermal_gap 1.4859)
		)
		(pad "" np_thru_hole circle
			(at 67.31 0)
			(size 0.254 0.254)
			(drill 3.2004)
			(layers "*.Cu" "*.Mask")
			(clearance 1.8288)
			(thermal_gap 1.8288)
		)
		(pad "P1_1" thru_hole circle
			(at 6.99008 0)
			(size 1.4224 1.4224)
			(drill 1.01981)
			(layers "*.Cu" "*.Mask")
			(remove_unused_layers no)
			(net "GND")
			(clearance 0.1651)
			(thermal_gap 0.1651)
		)
		(pad "P1_2" thru_hole circle
			(at 6.99008 -2.54)
			(size 1.4224 1.4224)
			(drill 1.01981)
			(layers "*.Cu" "*.Mask")
			(remove_unused_layers no)
			(net "GND")
			(clearance 0.1651)
			(thermal_gap 0.1651)
		)
		(pad "P1_3" thru_hole circle
			(at 6.99008 -5.08)
			(size 1.4224 1.4224)
			(drill 1.01981)
			(layers "*.Cu" "*.Mask")
			(remove_unused_layers no)
			(net "GND")
			(clearance 0.1651)
			(thermal_gap 0.1651)
		)
		(pad "P1_4" thru_hole circle
			(at 6.99008 -7.62)
			(size 1.4224 1.4224)
			(drill 1.01981)
			(layers "*.Cu" "*.Mask")
			(remove_unused_layers no)
			(net "GND")
			(clearance 0.1651)
			(thermal_gap 0.1651)
		)
		(pad "P1_5" thru_hole circle
			(at 9.53008 0)
			(size 1.4224 1.4224)
			(drill 1.01981)
			(layers "*.Cu" "*.Mask")
			(remove_unused_layers no)
			(net "GND")
			(clearance 0.1651)
			(thermal_gap 0.1651)
		)
		(pad "P1_6" thru_hole circle
			(at 9.53008 -2.54)
			(size 1.4224 1.4224)
			(drill 1.01981)
			(layers "*.Cu" "*.Mask")
			(remove_unused_layers no)
			(net "GND")
			(clearance 0.1651)
			(thermal_gap 0.1651)
		)
		(pad "P1_7" thru_hole circle
			(at 9.53008 -5.08)
			(size 1.4224 1.4224)
			(drill 1.01981)
			(layers "*.Cu" "*.Mask")
			(remove_unused_layers no)
			(net "GND")
			(clearance 0.1651)
			(thermal_gap 0.1651)
		)
		(pad "P1_8" thru_hole circle
			(at 9.53008 -7.62)
			(size 1.4224 1.4224)
			(drill 1.01981)
			(layers "*.Cu" "*.Mask")
			(remove_unused_layers no)
			(net "GND")
			(clearance 0.1651)
			(thermal_gap 0.1651)
		)
		(pad "P2_1" thru_hole circle
			(at 14.61008 0)
			(size 1.4224 1.4224)
			(drill 1.01981)
			(layers "*.Cu" "*.Mask")
			(remove_unused_layers no)
			(net "GND")
			(clearance 0.1651)
			(thermal_gap 0.1651)
		)
		(pad "P2_2" thru_hole circle
			(at 14.61008 -2.54)
			(size 1.4224 1.4224)
			(drill 1.01981)
			(layers "*.Cu" "*.Mask")
			(remove_unused_layers no)
			(net "GND")
			(clearance 0.1651)
			(thermal_gap 0.1651)
		)
		(pad "P2_3" thru_hole circle
			(at 14.61008 -5.08)
			(size 1.4224 1.4224)
			(drill 1.01981)
			(layers "*.Cu" "*.Mask")
			(remove_unused_layers no)
			(net "GND")
			(clearance 0.1651)
			(thermal_gap 0.1651)
		)
		(pad "P2_4" thru_hole circle
			(at 14.61008 -7.62)
			(size 1.4224 1.4224)
			(drill 1.01981)
			(layers "*.Cu" "*.Mask")
			(remove_unused_layers no)
			(net "GND")
			(clearance 0.1651)
			(thermal_gap 0.1651)
		)
		(pad "P2_5" thru_hole circle
			(at 17.15008 0)
			(size 1.4224 1.4224)
			(drill 1.01981)
			(layers "*.Cu" "*.Mask")
			(remove_unused_layers no)
			(net "GND")
			(clearance 0.1651)
			(thermal_gap 0.1651)
		)
		(pad "P2_6" thru_hole circle
			(at 17.15008 -2.54)
			(size 1.4224 1.4224)
			(drill 1.01981)
			(layers "*.Cu" "*.Mask")
			(remove_unused_layers no)
			(net "GND")
			(clearance 0.1651)
			(thermal_gap 0.1651)
		)
		(pad "P2_7" thru_hole circle
			(at 17.15008 -5.08)
			(size 1.4224 1.4224)
			(drill 1.01981)
			(layers "*.Cu" "*.Mask")
			(remove_unused_layers no)
			(net "GND")
			(clearance 0.1651)
			(thermal_gap 0.1651)
		)
		(pad "P2_8" thru_hole circle
			(at 17.15008 -7.62)
			(size 1.4224 1.4224)
			(drill 1.01981)
			(layers "*.Cu" "*.Mask")
			(remove_unused_layers no)
			(net "GND")
			(clearance 0.1651)
			(thermal_gap 0.1651)
		)
		(pad "P3_1" thru_hole circle
			(at 22.23008 0)
			(size 1.4224 1.4224)
			(drill 1.01981)
			(layers "*.Cu" "*.Mask")
			(remove_unused_layers no)
			(net "GND")
			(clearance 0.1651)
			(thermal_gap 0.1651)
		)
		(pad "P3_2" thru_hole circle
			(at 22.23008 -2.54)
			(size 1.4224 1.4224)
			(drill 1.01981)
			(layers "*.Cu" "*.Mask")
			(remove_unused_layers no)
			(net "GND")
			(clearance 0.1651)
			(thermal_gap 0.1651)
		)
		(pad "P3_3" thru_hole circle
			(at 22.23008 -5.08)
			(size 1.4224 1.4224)
			(drill 1.01981)
			(layers "*.Cu" "*.Mask")
			(remove_unused_layers no)
			(net "GND")
			(clearance 0.1651)
			(thermal_gap 0.1651)
		)
		(pad "P3_4" thru_hole circle
			(at 22.23008 -7.62)
			(size 1.4224 1.4224)
			(drill 1.01981)
			(layers "*.Cu" "*.Mask")
			(remove_unused_layers no)
			(net "GND")
			(clearance 0.1651)
			(thermal_gap 0.1651)
		)
		(pad "P3_5" thru_hole circle
			(at 24.77008 0)
			(size 1.4224 1.4224)
			(drill 1.01981)
			(layers "*.Cu" "*.Mask")
			(remove_unused_layers no)
			(net "GND")
			(clearance 0.1651)
			(thermal_gap 0.1651)
		)
		(pad "P3_6" thru_hole circle
			(at 24.77008 -2.54)
			(size 1.4224 1.4224)
			(drill 1.01981)
			(layers "*.Cu" "*.Mask")
			(remove_unused_layers no)
			(net "GND")
			(clearance 0.1651)
			(thermal_gap 0.1651)
		)
		(pad "P3_7" thru_hole circle
			(at 24.77008 -5.08)
			(size 1.4224 1.4224)
			(drill 1.01981)
			(layers "*.Cu" "*.Mask")
			(remove_unused_layers no)
			(net "GND")
			(clearance 0.1651)
			(thermal_gap 0.1651)
		)
		(pad "P3_8" thru_hole circle
			(at 24.77008 -7.62)
			(size 1.4224 1.4224)
			(drill 1.01981)
			(layers "*.Cu" "*.Mask")
			(remove_unused_layers no)
			(net "GND")
			(clearance 0.1651)
			(thermal_gap 0.1651)
		)
		(pad "P4_1" thru_hole circle
			(at 29.85008 0)
			(size 1.4224 1.4224)
			(drill 1.01981)
			(layers "*.Cu" "*.Mask")
			(remove_unused_layers no)
			(net "GND")
			(clearance 0.1651)
			(thermal_gap 0.1651)
		)
		(pad "P4_2" thru_hole circle
			(at 29.85008 -2.54)
			(size 1.4224 1.4224)
			(drill 1.01981)
			(layers "*.Cu" "*.Mask")
			(remove_unused_layers no)
			(net "GND")
			(clearance 0.1651)
			(thermal_gap 0.1651)
		)
		(pad "P4_3" thru_hole circle
			(at 29.85008 -5.08)
			(size 1.4224 1.4224)
			(drill 1.01981)
			(layers "*.Cu" "*.Mask")
			(remove_unused_layers no)
			(net "GND")
			(clearance 0.1651)
			(thermal_gap 0.1651)
		)
		(pad "P4_4" thru_hole circle
			(at 29.85008 -7.62)
			(size 1.4224 1.4224)
			(drill 1.01981)
			(layers "*.Cu" "*.Mask")
			(remove_unused_layers no)
			(net "GND")
			(clearance 0.1651)
			(thermal_gap 0.1651)
		)
		(pad "P4_5" thru_hole circle
			(at 32.39008 0)
			(size 1.4224 1.4224)
			(drill 1.01981)
			(layers "*.Cu" "*.Mask")
			(remove_unused_layers no)
			(net "GND")
			(clearance 0.1651)
			(thermal_gap 0.1651)
		)
		(pad "P4_6" thru_hole circle
			(at 32.39008 -2.54)
			(size 1.4224 1.4224)
			(drill 1.01981)
			(layers "*.Cu" "*.Mask")
			(remove_unused_layers no)
			(net "GND")
			(clearance 0.1651)
			(thermal_gap 0.1651)
		)
		(pad "P4_7" thru_hole circle
			(at 32.39008 -5.08)
			(size 1.4224 1.4224)
			(drill 1.01981)
			(layers "*.Cu" "*.Mask")
			(remove_unused_layers no)
			(net "GND")
			(clearance 0.1651)
			(thermal_gap 0.1651)
		)
		(pad "P4_8" thru_hole circle
			(at 32.39008 -7.62)
			(size 1.4224 1.4224)
			(drill 1.01981)
			(layers "*.Cu" "*.Mask")
			(remove_unused_layers no)
			(net "GND")
			(clearance 0.1651)
			(thermal_gap 0.1651)
		)
		(pad "P5_1" thru_hole circle
			(at 37.47008 0)
			(size 1.4224 1.4224)
			(drill 1.01981)
			(layers "*.Cu" "*.Mask")
			(remove_unused_layers no)
			(net "P12V_CLIP")
			(clearance 0.1651)
			(thermal_gap 0.1651)
		)
		(pad "P5_2" thru_hole circle
			(at 37.47008 -2.54)
			(size 1.4224 1.4224)
			(drill 1.01981)
			(layers "*.Cu" "*.Mask")
			(remove_unused_layers no)
			(net "P12V_CLIP")
			(clearance 0.1651)
			(thermal_gap 0.1651)
		)
		(pad "P5_3" thru_hole circle
			(at 37.47008 -5.08)
			(size 1.4224 1.4224)
			(drill 1.01981)
			(layers "*.Cu" "*.Mask")
			(remove_unused_layers no)
			(net "P12V_CLIP")
			(clearance 0.1651)
			(thermal_gap 0.1651)
		)
		(pad "P5_4" thru_hole circle
			(at 37.47008 -7.62)
			(size 1.4224 1.4224)
			(drill 1.01981)
			(layers "*.Cu" "*.Mask")
			(remove_unused_layers no)
			(net "P12V_CLIP")
			(clearance 0.1651)
			(thermal_gap 0.1651)
		)
		(pad "P5_5" thru_hole circle
			(at 40.01008 0)
			(size 1.4224 1.4224)
			(drill 1.01981)
			(layers "*.Cu" "*.Mask")
			(remove_unused_layers no)
			(net "P12V_CLIP")
			(clearance 0.1651)
			(thermal_gap 0.1651)
		)
		(pad "P5_6" thru_hole circle
			(at 40.01008 -2.54)
			(size 1.4224 1.4224)
			(drill 1.01981)
			(layers "*.Cu" "*.Mask")
			(remove_unused_layers no)
			(net "P12V_CLIP")
			(clearance 0.1651)
			(thermal_gap 0.1651)
		)
		(pad "P5_7" thru_hole circle
			(at 40.01008 -5.08)
			(size 1.4224 1.4224)
			(drill 1.01981)
			(layers "*.Cu" "*.Mask")
			(remove_unused_layers no)
			(net "P12V_CLIP")
			(clearance 0.1651)
			(thermal_gap 0.1651)
		)
		(pad "P5_8" thru_hole circle
			(at 40.01008 -7.62)
			(size 1.4224 1.4224)
			(drill 1.01981)
			(layers "*.Cu" "*.Mask")
			(remove_unused_layers no)
			(net "P12V_CLIP")
			(clearance 0.1651)
			(thermal_gap 0.1651)
		)
		(pad "P6_1" thru_hole circle
			(at 45.09008 0)
			(size 1.4224 1.4224)
			(drill 1.01981)
			(layers "*.Cu" "*.Mask")
			(remove_unused_layers no)
			(net "P12V_CLIP")
			(clearance 0.1651)
			(thermal_gap 0.1651)
		)
		(pad "P6_2" thru_hole circle
			(at 45.09008 -2.54)
			(size 1.4224 1.4224)
			(drill 1.01981)
			(layers "*.Cu" "*.Mask")
			(remove_unused_layers no)
			(net "P12V_CLIP")
			(clearance 0.1651)
			(thermal_gap 0.1651)
		)
		(pad "P6_3" thru_hole circle
			(at 45.09008 -5.08)
			(size 1.4224 1.4224)
			(drill 1.01981)
			(layers "*.Cu" "*.Mask")
			(remove_unused_layers no)
			(net "P12V_CLIP")
			(clearance 0.1651)
			(thermal_gap 0.1651)
		)
		(pad "P6_4" thru_hole circle
			(at 45.09008 -7.62)
			(size 1.4224 1.4224)
			(drill 1.01981)
			(layers "*.Cu" "*.Mask")
			(remove_unused_layers no)
			(net "P12V_CLIP")
			(clearance 0.1651)
			(thermal_gap 0.1651)
		)
		(pad "P6_5" thru_hole circle
			(at 47.63008 0)
			(size 1.4224 1.4224)
			(drill 1.01981)
			(layers "*.Cu" "*.Mask")
			(remove_unused_layers no)
			(net "P12V_CLIP")
			(clearance 0.1651)
			(thermal_gap 0.1651)
		)
		(pad "P6_6" thru_hole circle
			(at 47.63008 -2.54)
			(size 1.4224 1.4224)
			(drill 1.01981)
			(layers "*.Cu" "*.Mask")
			(remove_unused_layers no)
			(net "P12V_CLIP")
			(clearance 0.1651)
			(thermal_gap 0.1651)
		)
		(pad "P6_7" thru_hole circle
			(at 47.63008 -5.08)
			(size 1.4224 1.4224)
			(drill 1.01981)
			(layers "*.Cu" "*.Mask")
			(remove_unused_layers no)
			(net "P12V_CLIP")
			(clearance 0.1651)
			(thermal_gap 0.1651)
		)
		(pad "P6_8" thru_hole circle
			(at 47.63008 -7.62)
			(size 1.4224 1.4224)
			(drill 1.01981)
			(layers "*.Cu" "*.Mask")
			(remove_unused_layers no)
			(net "P12V_CLIP")
			(clearance 0.1651)
			(thermal_gap 0.1651)
		)
		(pad "P7_1" thru_hole circle
			(at 52.71008 0)
			(size 1.4224 1.4224)
			(drill 1.01981)
			(layers "*.Cu" "*.Mask")
			(remove_unused_layers no)
			(net "P12V_CLIP")
			(clearance 0.1651)
			(thermal_gap 0.1651)
		)
		(pad "P7_2" thru_hole circle
			(at 52.71008 -2.54)
			(size 1.4224 1.4224)
			(drill 1.01981)
			(layers "*.Cu" "*.Mask")
			(remove_unused_layers no)
			(net "P12V_CLIP")
			(clearance 0.1651)
			(thermal_gap 0.1651)
		)
		(pad "P7_3" thru_hole circle
			(at 52.71008 -5.08)
			(size 1.4224 1.4224)
			(drill 1.01981)
			(layers "*.Cu" "*.Mask")
			(remove_unused_layers no)
			(net "P12V_CLIP")
			(clearance 0.1651)
			(thermal_gap 0.1651)
		)
		(pad "P7_4" thru_hole circle
			(at 52.71008 -7.62)
			(size 1.4224 1.4224)
			(drill 1.01981)
			(layers "*.Cu" "*.Mask")
			(remove_unused_layers no)
			(net "P12V_CLIP")
			(clearance 0.1651)
			(thermal_gap 0.1651)
		)
		(pad "P7_5" thru_hole circle
			(at 55.25008 0)
			(size 1.4224 1.4224)
			(drill 1.01981)
			(layers "*.Cu" "*.Mask")
			(remove_unused_layers no)
			(net "P12V_CLIP")
			(clearance 0.1651)
			(thermal_gap 0.1651)
		)
		(pad "P7_6" thru_hole circle
			(at 55.25008 -2.54)
			(size 1.4224 1.4224)
			(drill 1.01981)
			(layers "*.Cu" "*.Mask")
			(remove_unused_layers no)
			(net "P12V_CLIP")
			(clearance 0.1651)
			(thermal_gap 0.1651)
		)
		(pad "P7_7" thru_hole circle
			(at 55.25008 -5.08)
			(size 1.4224 1.4224)
			(drill 1.01981)
			(layers "*.Cu" "*.Mask")
			(remove_unused_layers no)
			(net "P12V_CLIP")
			(clearance 0.1651)
			(thermal_gap 0.1651)
		)
		(pad "P7_8" thru_hole circle
			(at 55.25008 -7.62)
			(size 1.4224 1.4224)
			(drill 1.01981)
			(layers "*.Cu" "*.Mask")
			(remove_unused_layers no)
			(net "P12V_CLIP")
			(clearance 0.1651)
			(thermal_gap 0.1651)
		)
	)
)
